(kicad_pcb
	(version 20221018)
	(generator pcbnew)
	(general
    (thickness 1.518)
  )
	(paper "A4")
	(title_block
    (title "Kria K26 Devboard")
    (date "2024-03-26")
    (rev "1.2.5")
    (comment 1 "www.antmicro.com")
    (comment 2 "Antmicro Ltd.")
		(comment 9 "footprints 535-544 of 660")
	)
	(layers
    (0 "F.Cu" mixed)
    (1 "In1.Cu" power)
    (2 "In2.Cu" mixed)
    (3 "In3.Cu" power)
    (4 "In4.Cu" mixed)
    (5 "In5.Cu" power)
    (6 "In6.Cu" mixed)
    (31 "B.Cu" power)
    (32 "B.Adhes" user "B.Adhesive")
    (33 "F.Adhes" user "F.Adhesive")
    (34 "B.Paste" user)
    (35 "F.Paste" user)
    (36 "B.SilkS" user "B.Silkscreen")
    (37 "F.SilkS" user "F.Silkscreen")
    (38 "B.Mask" user)
    (39 "F.Mask" user)
    (40 "Dwgs.User" user "User.Drawings")
    (41 "Cmts.User" user "User.Comments")
    (42 "Eco1.User" user "User.Eco1")
    (43 "Eco2.User" user "User.Eco2")
    (44 "Edge.Cuts" user)
    (45 "Margin" user)
    (46 "B.CrtYd" user "B.Courtyard")
    (47 "F.CrtYd" user "F.Courtyard")
    (48 "B.Fab" user)
    (49 "F.Fab" user)
  )
	(footprint "kria-k26-devboard-footprints:C_0402_1005Metric" (layer "B.Cu")
    (at 137.75 67.55)
    (descr "Capacitor SMD 0402")
    (tags "capacitor SMD 0402")
    (property "Author" "Antmicro")
    (property "Dielectric" "X5R")
    (property "License" "Apache-2.0")
    (property "MPN" "GRM155R61H104KE14D")
    (property "Manufacturer" "Murata")
    (property "Sheetfile" "usb.kicad_sch")
    (property "Sheetname" "USB")
    (property "Val" "100n")
    (property "Voltage" "50V")
    (property "ki_description" " ")
    (attr smd)
    (fp_text reference "C74" (at 3.04 0.35 180) (layer "B.SilkS")
        (effects (font (size 0.7 0.7) (thickness 0.15)) (justify left bottom mirror))
    )
    (fp_text value "C_100n_0402" (at 0 -1.4 180) (layer "B.Fab") hide
        (effects (font (size 0.7 0.7) (thickness 0.15)) (justify left bottom mirror))
    )
    (fp_text user "Author: Antmicro" (at -0.932 -4.17 180) (layer "B.Fab") hide
        (effects (font (size 0.7 0.7) (thickness 0.15)) (justify left bottom mirror))
    )
    (fp_text user "License: Apache-2.0" (at -0.932 -5.17 180) (layer "B.Fab") hide
        (effects (font (size 0.7 0.7) (thickness 0.15)) (justify left bottom mirror))
    )
    (fp_text user "${REFERENCE}" (at -0.932 -3.168 180) (layer "B.Fab") hide
        (effects (font (size 0.7 0.7) (thickness 0.15)) (justify left bottom mirror))
    )
    (fp_rect (start -0.94 0.47) (end 0.94 -0.47)
      (stroke (width 0.05) (type solid)) (fill none) (layer "B.CrtYd"))
    (fp_rect (start -0.499 0.249) (end 0.499 -0.249)
      (stroke (width 0.15) (type solid)) (fill none) (layer "B.Fab"))
    (pad "1" smd roundrect (at -0.484 0) (size 0.59 0.64) (layers "B.Cu" "B.Paste" "B.Mask") (roundrect_rratio 0.25)
      (net 85 "/USB/USB2_VBUS") (pintype "passive"))
    (pad "2" smd roundrect (at 0.484 0) (size 0.59 0.64) (layers "B.Cu" "B.Paste" "B.Mask") (roundrect_rratio 0.25)
      (net 1 "GND") (pintype "passive"))
  )
	(footprint "kria-k26-devboard-footprints:C_0402_1005Metric" (layer "B.Cu")
    (at 118.35 65.55)
    (descr "Capacitor SMD 0402")
    (tags "capacitor SMD 0402")
    (property "Author" "Antmicro")
    (property "Dielectric" "")
    (property "License" "Apache-2.0")
    (property "MPN" "CC0402MRX5R5BB106")
    (property "Manufacturer" "Yaego")
    (property "Sheetfile" "usb.kicad_sch")
    (property "Sheetname" "USB")
    (property "Val" "10u")
    (property "Voltage" "")
    (property "ki_description" " ")
    (attr smd)
    (fp_text reference "C82" (at 3.04 0.32 180) (layer "B.SilkS")
        (effects (font (size 0.7 0.7) (thickness 0.15)) (justify left bottom mirror))
    )
    (fp_text value "C_10u_0402" (at 0 -1.4 180) (layer "B.Fab") hide
        (effects (font (size 0.7 0.7) (thickness 0.15)) (justify left bottom mirror))
    )
    (fp_text user "License: Apache-2.0" (at -0.932 -5.17 180) (layer "B.Fab") hide
        (effects (font (size 0.7 0.7) (thickness 0.15)) (justify left bottom mirror))
    )
    (fp_text user "Author: Antmicro" (at -0.932 -4.17 180) (layer "B.Fab") hide
        (effects (font (size 0.7 0.7) (thickness 0.15)) (justify left bottom mirror))
    )
    (fp_text user "${REFERENCE}" (at -0.932 -3.168 180) (layer "B.Fab") hide
        (effects (font (size 0.7 0.7) (thickness 0.15)) (justify left bottom mirror))
    )
    (fp_rect (start -0.94 0.47) (end 0.94 -0.47)
      (stroke (width 0.05) (type solid)) (fill none) (layer "B.CrtYd"))
    (fp_rect (start -0.499 0.249) (end 0.499 -0.249)
      (stroke (width 0.15) (type solid)) (fill none) (layer "B.Fab"))
    (pad "1" smd roundrect (at -0.484 0) (size 0.59 0.64) (layers "B.Cu" "B.Paste" "B.Mask") (roundrect_rratio 0.25)
      (net 87 "/USB/USB4_VBUS") (pintype "passive"))
    (pad "2" smd roundrect (at 0.484 0) (size 0.59 0.64) (layers "B.Cu" "B.Paste" "B.Mask") (roundrect_rratio 0.25)
      (net 1 "GND") (pintype "passive"))
  )
	(footprint "kria-k26-devboard-footprints:C_0402_1005Metric" (layer "B.Cu")
    (at 112.95 63.8 90)
    (descr "Capacitor SMD 0402")
    (tags "capacitor SMD 0402")
    (property "Author" "Antmicro")
    (property "Dielectric" "X5R")
    (property "License" "Apache-2.0")
    (property "MPN" "GRM155R61H104KE14D")
    (property "Manufacturer" "Murata")
    (property "Sheetfile" "usb.kicad_sch")
    (property "Sheetname" "USB")
    (property "Val" "100n")
    (property "Voltage" "50V")
    (property "ki_description" " ")
    (attr smd)
    (fp_text reference "C87" (at 3.13 0.41 270) (layer "B.SilkS")
        (effects (font (size 0.7 0.7) (thickness 0.15)) (justify left bottom mirror))
    )
    (fp_text value "C_100n_0402" (at 0 -1.4 270) (layer "B.Fab") hide
        (effects (font (size 0.7 0.7) (thickness 0.15)) (justify left bottom mirror))
    )
    (fp_text user "License: Apache-2.0" (at -0.932 -5.17 270) (layer "B.Fab") hide
        (effects (font (size 0.7 0.7) (thickness 0.15)) (justify left bottom mirror))
    )
    (fp_text user "Author: Antmicro" (at -0.932 -4.17 270) (layer "B.Fab") hide
        (effects (font (size 0.7 0.7) (thickness 0.15)) (justify left bottom mirror))
    )
    (fp_text user "${REFERENCE}" (at -0.932 -3.168 270) (layer "B.Fab") hide
        (effects (font (size 0.7 0.7) (thickness 0.15)) (justify left bottom mirror))
    )
    (fp_rect (start -0.94 0.47) (end 0.94 -0.47)
      (stroke (width 0.05) (type solid)) (fill none) (layer "B.CrtYd"))
    (fp_rect (start -0.499 0.249) (end 0.499 -0.249)
      (stroke (width 0.15) (type solid)) (fill none) (layer "B.Fab"))
    (pad "1" smd roundrect (at -0.484 0 90) (size 0.59 0.64) (layers "B.Cu" "B.Paste" "B.Mask") (roundrect_rratio 0.25)
      (net 86 "/USB/USB3_VBUS") (pintype "passive"))
    (pad "2" smd roundrect (at 0.484 0 90) (size 0.59 0.64) (layers "B.Cu" "B.Paste" "B.Mask") (roundrect_rratio 0.25)
      (net 1 "GND") (pintype "passive"))
  )
	(footprint "kria-k26-devboard-footprints:C_0402_1005Metric" (layer "B.Cu")
    (at 137.75 66.55)
    (descr "Capacitor SMD 0402")
    (tags "capacitor SMD 0402")
    (property "Author" "Antmicro")
    (property "Dielectric" "")
    (property "License" "Apache-2.0")
    (property "MPN" "CC0402MRX5R5BB106")
    (property "Manufacturer" "Yaego")
    (property "Sheetfile" "usb.kicad_sch")
    (property "Sheetname" "USB")
    (property "Val" "10u")
    (property "Voltage" "")
    (property "ki_description" " ")
    (attr smd)
    (fp_text reference "C70" (at 3.04 0.35 180) (layer "B.SilkS")
        (effects (font (size 0.7 0.7) (thickness 0.15)) (justify left bottom mirror))
    )
    (fp_text value "C_10u_0402" (at 0 -1.4 180) (layer "B.Fab") hide
        (effects (font (size 0.7 0.7) (thickness 0.15)) (justify left bottom mirror))
    )
    (fp_text user "License: Apache-2.0" (at -0.932 -5.17 180) (layer "B.Fab") hide
        (effects (font (size 0.7 0.7) (thickness 0.15)) (justify left bottom mirror))
    )
    (fp_text user "${REFERENCE}" (at -0.932 -3.168 180) (layer "B.Fab") hide
        (effects (font (size 0.7 0.7) (thickness 0.15)) (justify left bottom mirror))
    )
    (fp_text user "Author: Antmicro" (at -0.932 -4.17 180) (layer "B.Fab") hide
        (effects (font (size 0.7 0.7) (thickness 0.15)) (justify left bottom mirror))
    )
    (fp_rect (start -0.94 0.47) (end 0.94 -0.47)
      (stroke (width 0.05) (type solid)) (fill none) (layer "B.CrtYd"))
    (fp_rect (start -0.499 0.249) (end 0.499 -0.249)
      (stroke (width 0.15) (type solid)) (fill none) (layer "B.Fab"))
    (pad "1" smd roundrect (at -0.484 0) (size 0.59 0.64) (layers "B.Cu" "B.Paste" "B.Mask") (roundrect_rratio 0.25)
      (net 85 "/USB/USB2_VBUS") (pintype "passive"))
    (pad "2" smd roundrect (at 0.484 0) (size 0.59 0.64) (layers "B.Cu" "B.Paste" "B.Mask") (roundrect_rratio 0.25)
      (net 1 "GND") (pintype "passive"))
  )
	(footprint "kria-k26-devboard-footprints:C_0402_1005Metric" (layer "B.Cu")
    (at 118.35 66.550001)
    (descr "Capacitor SMD 0402")
    (tags "capacitor SMD 0402")
    (property "Author" "Antmicro")
    (property "Dielectric" "")
    (property "License" "Apache-2.0")
    (property "MPN" "CC0402MRX5R5BB106")
    (property "Manufacturer" "Yaego")
    (property "Sheetfile" "usb.kicad_sch")
    (property "Sheetname" "USB")
    (property "Val" "10u")
    (property "Voltage" "")
    (property "ki_description" " ")
    (attr smd)
    (fp_text reference "C85" (at 3.04 0.32 180) (layer "B.SilkS")
        (effects (font (size 0.7 0.7) (thickness 0.15)) (justify left bottom mirror))
    )
    (fp_text value "C_10u_0402" (at 0 -1.4 180) (layer "B.Fab") hide
        (effects (font (size 0.7 0.7) (thickness 0.15)) (justify left bottom mirror))
    )
    (fp_text user "${REFERENCE}" (at -0.932 -3.168 180) (layer "B.Fab") hide
        (effects (font (size 0.7 0.7) (thickness 0.15)) (justify left bottom mirror))
    )
    (fp_text user "Author: Antmicro" (at -0.932 -4.17 180) (layer "B.Fab") hide
        (effects (font (size 0.7 0.7) (thickness 0.15)) (justify left bottom mirror))
    )
    (fp_text user "License: Apache-2.0" (at -0.932 -5.17 180) (layer "B.Fab") hide
        (effects (font (size 0.7 0.7) (thickness 0.15)) (justify left bottom mirror))
    )
    (fp_rect (start -0.94 0.47) (end 0.94 -0.47)
      (stroke (width 0.05) (type solid)) (fill none) (layer "B.CrtYd"))
    (fp_rect (start -0.499 0.249) (end 0.499 -0.249)
      (stroke (width 0.15) (type solid)) (fill none) (layer "B.Fab"))
    (pad "1" smd roundrect (at -0.484 0) (size 0.59 0.64) (layers "B.Cu" "B.Paste" "B.Mask") (roundrect_rratio 0.25)
      (net 87 "/USB/USB4_VBUS") (pintype "passive"))
    (pad "2" smd roundrect (at 0.484 0) (size 0.59 0.64) (layers "B.Cu" "B.Paste" "B.Mask") (roundrect_rratio 0.25)
      (net 1 "GND") (pintype "passive"))
  )
	(footprint "kria-k26-devboard-footprints:C_0402_1005Metric" (layer "B.Cu")
    (at 113.95 63.8 90)
    (descr "Capacitor SMD 0402")
    (tags "capacitor SMD 0402")
    (property "Author" "Antmicro")
    (property "Dielectric" "")
    (property "License" "Apache-2.0")
    (property "MPN" "CC0402MRX5R5BB106")
    (property "Manufacturer" "Yaego")
    (property "Sheetfile" "usb.kicad_sch")
    (property "Sheetname" "USB")
    (property "Val" "10u")
    (property "Voltage" "")
    (property "ki_description" " ")
    (attr smd)
    (fp_text reference "C84" (at 3.13 0.41 270) (layer "B.SilkS")
        (effects (font (size 0.7 0.7) (thickness 0.15)) (justify left bottom mirror))
    )
    (fp_text value "C_10u_0402" (at 0 -1.4 270) (layer "B.Fab") hide
        (effects (font (size 0.7 0.7) (thickness 0.15)) (justify left bottom mirror))
    )
    (fp_text user "Author: Antmicro" (at -0.932 -4.17 270) (layer "B.Fab") hide
        (effects (font (size 0.7 0.7) (thickness 0.15)) (justify left bottom mirror))
    )
    (fp_text user "${REFERENCE}" (at -0.932 -3.168 270) (layer "B.Fab") hide
        (effects (font (size 0.7 0.7) (thickness 0.15)) (justify left bottom mirror))
    )
    (fp_text user "License: Apache-2.0" (at -0.932 -5.17 270) (layer "B.Fab") hide
        (effects (font (size 0.7 0.7) (thickness 0.15)) (justify left bottom mirror))
    )
    (fp_rect (start -0.94 0.47) (end 0.94 -0.47)
      (stroke (width 0.05) (type solid)) (fill none) (layer "B.CrtYd"))
    (fp_rect (start -0.499 0.249) (end 0.499 -0.249)
      (stroke (width 0.15) (type solid)) (fill none) (layer "B.Fab"))
    (pad "1" smd roundrect (at -0.484 0 90) (size 0.59 0.64) (layers "B.Cu" "B.Paste" "B.Mask") (roundrect_rratio 0.25)
      (net 86 "/USB/USB3_VBUS") (pintype "passive"))
    (pad "2" smd roundrect (at 0.484 0 90) (size 0.59 0.64) (layers "B.Cu" "B.Paste" "B.Mask") (roundrect_rratio 0.25)
      (net 1 "GND") (pintype "passive"))
  )
	(footprint "kria-k26-devboard-footprints:C_0402_1005Metric" (layer "B.Cu")
    (at 132.375736 63.741421 90)
    (descr "Capacitor SMD 0402")
    (tags "capacitor SMD 0402")
    (property "Author" "Antmicro")
    (property "Dielectric" "")
    (property "License" "Apache-2.0")
    (property "MPN" "CC0402MRX5R5BB106")
    (property "Manufacturer" "Yaego")
    (property "Sheetfile" "usb.kicad_sch")
    (property "Sheetname" "USB")
    (property "Val" "10u")
    (property "Voltage" "")
    (property "ki_description" " ")
    (attr smd)
    (fp_text reference "C72" (at 3.781421 0.36 270) (layer "B.SilkS")
        (effects (font (size 0.7 0.7) (thickness 0.15)) (justify left bottom mirror))
    )
    (fp_text value "C_10u_0402" (at 0 -1.4 270) (layer "B.Fab") hide
        (effects (font (size 0.7 0.7) (thickness 0.15)) (justify left bottom mirror))
    )
    (fp_text user "Author: Antmicro" (at -0.932 -4.17 270) (layer "B.Fab") hide
        (effects (font (size 0.7 0.7) (thickness 0.15)) (justify left bottom mirror))
    )
    (fp_text user "License: Apache-2.0" (at -0.932 -5.17 270) (layer "B.Fab") hide
        (effects (font (size 0.7 0.7) (thickness 0.15)) (justify left bottom mirror))
    )
    (fp_text user "${REFERENCE}" (at -0.932 -3.168 270) (layer "B.Fab") hide
        (effects (font (size 0.7 0.7) (thickness 0.15)) (justify left bottom mirror))
    )
    (fp_rect (start -0.94 0.47) (end 0.94 -0.47)
      (stroke (width 0.05) (type solid)) (fill none) (layer "B.CrtYd"))
    (fp_rect (start -0.499 0.249) (end 0.499 -0.249)
      (stroke (width 0.15) (type solid)) (fill none) (layer "B.Fab"))
    (pad "1" smd roundrect (at -0.484 0 90) (size 0.59 0.64) (layers "B.Cu" "B.Paste" "B.Mask") (roundrect_rratio 0.25)
      (net 64 "/USB/USB1_VBUS") (pintype "passive"))
    (pad "2" smd roundrect (at 0.484 0 90) (size 0.59 0.64) (layers "B.Cu" "B.Paste" "B.Mask") (roundrect_rratio 0.25)
      (net 1 "GND") (pintype "passive"))
  )
	(footprint "kria-k26-devboard-footprints:C_0402_1005Metric" (layer "B.Cu")
    (at 99.4 71.1 -90)
    (descr "Capacitor SMD 0402")
    (tags "capacitor SMD 0402")
    (property "Author" "Antmicro")
    (property "Dielectric" "X5R")
    (property "License" "Apache-2.0")
    (property "MPN" "GRM155R61H104KE14D")
    (property "Manufacturer" "Murata")
    (property "Sheetfile" "kria-k26-devboard.kicad_sch")
    (property "Sheetname" "")
    (property "Val" "100n")
    (property "Voltage" "50V")
    (property "ki_description" " ")
    (attr smd)
    (fp_text reference "C2" (at 0.91 -0.41 90) (layer "B.SilkS")
        (effects (font (size 0.7 0.7) (thickness 0.15)) (justify left bottom mirror))
    )
    (fp_text value "C_100n_0402" (at 0 -1.4 90) (layer "B.Fab") hide
        (effects (font (size 0.7 0.7) (thickness 0.15)) (justify left bottom mirror))
    )
    (fp_text user "${REFERENCE}" (at -0.932 -3.168 90) (layer "B.Fab") hide
        (effects (font (size 0.7 0.7) (thickness 0.15)) (justify left bottom mirror))
    )
    (fp_text user "Author: Antmicro" (at -0.932 -4.17 90) (layer "B.Fab") hide
        (effects (font (size 0.7 0.7) (thickness 0.15)) (justify left bottom mirror))
    )
    (fp_text user "License: Apache-2.0" (at -0.932 -5.17 90) (layer "B.Fab") hide
        (effects (font (size 0.7 0.7) (thickness 0.15)) (justify left bottom mirror))
    )
    (fp_rect (start -0.94 0.47) (end 0.94 -0.47)
      (stroke (width 0.05) (type solid)) (fill none) (layer "B.CrtYd"))
    (fp_rect (start -0.499 0.249) (end 0.499 -0.249)
      (stroke (width 0.15) (type solid)) (fill none) (layer "B.Fab"))
    (pad "1" smd roundrect (at -0.484 0 270) (size 0.59 0.64) (layers "B.Cu" "B.Paste" "B.Mask") (roundrect_rratio 0.25)
      (net 319 "SH_UP") (pintype "passive"))
    (pad "2" smd roundrect (at 0.484 0 270) (size 0.59 0.64) (layers "B.Cu" "B.Paste" "B.Mask") (roundrect_rratio 0.25)
      (net 1 "GND") (pintype "passive"))
  )
	(footprint "kria-k26-devboard-footprints:R_0402_1005Metric" (layer "B.Cu")
    (at 150.929289 146.887868)
    (descr "Resistor SMD 0402")
    (tags "resistor SMD 0402")
    (property "Author" "Antmicro")
    (property "License" "Apache-2.0")
    (property "MPN" "CR0402-FX-3300GLF")
    (property "Manufacturer" "Bourns")
    (property "Sheetfile" "kria-k26-devboard.kicad_sch")
    (property "Sheetname" "")
    (property "Tolerance" "1%")
    (property "Val" "330R")
    (property "ki_description" "330R resistor in 0402 package with 1% tolerance")
    (attr smd)
    (fp_text reference "R1" (at 2.360711 0.342132 180) (layer "B.SilkS")
        (effects (font (size 0.7 0.7) (thickness 0.15)) (justify left bottom mirror))
    )
    (fp_text value "R_330R_0402" (at 0 -1.4 180) (layer "B.Fab") hide
        (effects (font (size 0.7 0.7) (thickness 0.15)) (justify left bottom mirror))
    )
    (fp_text user "${REFERENCE}" (at -0.95 -3.168 180) (layer "B.Fab") hide
        (effects (font (size 0.7 0.7) (thickness 0.15)) (justify left bottom mirror))
    )
    (fp_text user "Author: Antmicro" (at -0.95 -4.169 180) (layer "B.Fab") hide
        (effects (font (size 0.7 0.7) (thickness 0.15)) (justify left bottom mirror))
    )
    (fp_text user "License: Apache-2.0" (at -0.95 -5.169 180) (layer "B.Fab") hide
        (effects (font (size 0.7 0.7) (thickness 0.15)) (justify left bottom mirror))
    )
    (fp_rect (start -0.93 0.47) (end 0.93 -0.47)
      (stroke (width 0.05) (type solid)) (fill none) (layer "B.CrtYd"))
    (fp_rect (start -0.5 0.25) (end 0.5 -0.25)
      (stroke (width 0.15) (type solid)) (fill none) (layer "B.Fab"))
    (pad "1" smd roundrect (at -0.485 0) (size 0.59 0.64) (layers "B.Cu" "B.Paste" "B.Mask") (roundrect_rratio 0.25)
      (net 318 "SH_DOWN") (pintype "passive"))
    (pad "2" smd roundrect (at 0.485 0) (size 0.59 0.64) (layers "B.Cu" "B.Paste" "B.Mask") (roundrect_rratio 0.25)
      (net 1 "GND") (pintype "passive"))
  )
	(footprint "kria-k26-devboard-footprints:R_0402_1005Metric" (layer "B.Cu")
    (at 100.35 71.1 -90)
    (descr "Resistor SMD 0402")
    (tags "resistor SMD 0402")
    (property "Author" "Antmicro")
    (property "License" "Apache-2.0")
    (property "MPN" "CR0402-FX-3300GLF")
    (property "Manufacturer" "Bourns")
    (property "Sheetfile" "kria-k26-devboard.kicad_sch")
    (property "Sheetname" "")
    (property "Tolerance" "1%")
    (property "Val" "330R")
    (property "ki_description" "330R resistor in 0402 package with 1% tolerance")
    (attr smd)
    (fp_text reference "R2" (at 0.909 -0.41 90) (layer "B.SilkS")
        (effects (font (size 0.7 0.7) (thickness 0.15)) (justify left bottom mirror))
    )
    (fp_text value "R_330R_0402" (at 0 -1.4 90) (layer "B.Fab") hide
        (effects (font (size 0.7 0.7) (thickness 0.15)) (justify left bottom mirror))
    )
    (fp_text user "${REFERENCE}" (at -0.95 -3.168 90) (layer "B.Fab") hide
        (effects (font (size 0.7 0.7) (thickness 0.15)) (justify left bottom mirror))
    )
    (fp_text user "License: Apache-2.0" (at -0.95 -5.169 90) (layer "B.Fab") hide
        (effects (font (size 0.7 0.7) (thickness 0.15)) (justify left bottom mirror))
    )
    (fp_text user "Author: Antmicro" (at -0.95 -4.169 90) (layer "B.Fab") hide
        (effects (font (size 0.7 0.7) (thickness 0.15)) (justify left bottom mirror))
    )
    (fp_rect (start -0.93 0.47) (end 0.93 -0.47)
      (stroke (width 0.05) (type solid)) (fill none) (layer "B.CrtYd"))
    (fp_rect (start -0.5 0.25) (end 0.5 -0.25)
      (stroke (width 0.15) (type solid)) (fill none) (layer "B.Fab"))
    (pad "1" smd roundrect (at -0.485 0 270) (size 0.59 0.64) (layers "B.Cu" "B.Paste" "B.Mask") (roundrect_rratio 0.25)
      (net 319 "SH_UP") (pintype "passive"))
    (pad "2" smd roundrect (at 0.485 0 270) (size 0.59 0.64) (layers "B.Cu" "B.Paste" "B.Mask") (roundrect_rratio 0.25)
      (net 1 "GND") (pintype "passive"))
  )
)
